G04 ================== begin FILE IDENTIFICATION RECORD ==================*
G04 Layout Name:  14545-sa.brd*
G04 Film Name:    P_OUTLINE*
G04 File Format:  Gerber RS274X*
G04 File Origin:  Cadence Allegro 16.5-S056*
G04 Origin Date:  Fri Aug 01 17:58:02 2014*
G04 *
G04 Layer:  BOARD GEOMETRY/PANEL_OUTLINE*
G04 *
G04 Offset:    (0.00 0.00)*
G04 Mirror:    No*
G04 Mode:      Positive*
G04 Rotation:  0*
G04 FullContactRelief:  No*
G04 UndefLineWidth:     6.00*
G04 ================== end FILE IDENTIFICATION RECORD ====================*
%FSLAX35Y35*MOIN*%
%IR0*IPPOS*OFA0.00000B0.00000*MIA0B0*SFA1.00000B1.00000*%
%ADD10C,.006*%
G75*
%LPD*%
G75*
G54D10*
G01X-78741Y15000D02*
G03X-63741Y0I15000J0D01*
G01X-78741Y15000D02*
Y120047D01*
G01X-63741Y135047D02*
G03X-78741Y120047I0J-15000D01*
G01Y298866D02*
G03X-63741Y283866I15000J0D01*
G01X-78741Y319646D02*
Y298866D01*
G01X-63741Y334646D02*
G03X-78741Y319646I0J-15000D01*
G01Y908315D02*
G03X-63741Y893315I15000J0D01*
G01X-78741Y908315D02*
Y1104299D01*
G01X-63741Y1119299D02*
G03X-78741Y1104299I0J-15000D01*
G01Y1283118D02*
G03X-63741Y1268118I15000J0D01*
G01X-78741Y1304285D02*
Y1283118D01*
G01X-63741Y1319285D02*
G03X-78741Y1304285I0J-15000D01*
G01Y1892953D02*
G03X-63741Y1877953I15000J0D01*
G01X-78741Y1892953D02*
Y1977126D01*
G01X-63741Y1992126D02*
G03X-78741Y1977126I0J-15000D01*
G01X19882Y1197834D02*
X1969D01*
X0Y1195865D01*
Y832479D01*
X1969Y830511D01*
X19882D01*
G02Y823030I0J-3741D01*
G01X1969D01*
X0Y821062D01*
Y423030D01*
X1969Y421062D01*
X19882D01*
G02Y413582I0J-3740D01*
G01X1969D01*
X0Y411613D01*
Y223030D01*
X1969Y221062D01*
X19882D01*
G02Y213582I0J-3740D01*
G01X1969D01*
X0Y211613D01*
Y3936D01*
G03X3937Y-1I3937J0D01*
G01X1029528D01*
G03X1033465Y3936I0J3937D01*
G01Y1424881D01*
X1029528Y1428818D01*
X1024213D01*
G02X1019291Y1433739I-1J4921D01*
G01Y1607932D01*
X1015354Y1611869D01*
X989744D01*
G02Y1616082I0J2107D01*
G01X1015354D01*
X1019291Y1620019D01*
Y1676495D01*
G02X1024213Y1681416I4921J0D01*
G01X1029528D01*
X1033465Y1685353D01*
Y1988188D01*
G03X1029528Y1992125I-3937J0D01*
G01X3937D01*
G03X0Y1988188I0J-3937D01*
G01Y1816731D01*
X1969Y1814763D01*
X19882D01*
G02Y1807282I0J-3741D01*
G01X1969D01*
X0Y1805314D01*
Y1407282D01*
X1969Y1405314D01*
X19882D01*
G02Y1397834I0J-3740D01*
G01X1969D01*
X0Y1395865D01*
Y1207282D01*
X1969Y1205314D01*
X19882D01*
G02Y1197834I0J-3740D01*
G01X-7875Y0D02*
X-63741D01*
G01X-7875Y41772D02*
Y104969D01*
G01Y17252D02*
Y0D01*
G01Y41772D02*
G03X-1I3937J-1D01*
G01Y17213D02*
G03X-7875I-3937J0D01*
G01Y41772D02*
G03X-1I3937J-1D01*
G01Y17213D02*
G03X-7875I-3937J0D01*
G01Y129516D02*
Y135047D01*
G01D02*
X-63741D01*
G01X-7875Y129516D02*
G03X-1I3937J0D01*
G01Y104958D02*
G03X-7875I-3937J0D01*
G01Y283866D02*
Y300383D01*
G01X-19814Y283866D02*
X-63741D01*
G01X-7875D02*
X-19814D01*
G01X-1Y300383D02*
G03X-7875I-3937J0D01*
G01Y331986D02*
Y324003D01*
G01Y331986D02*
Y334646D01*
G01D02*
X-63741D01*
G01X-7875Y324003D02*
G03X-1I3937J0D01*
G01X-7875Y905988D02*
Y893315D01*
G01D02*
X-63741D01*
G01X-7875Y1069005D02*
Y933234D01*
G01D02*
G03X-1I3937J0D01*
G01Y905988D02*
G03X-7875I-3937J0D01*
G01Y1108863D02*
Y1119299D01*
G01X-19126D02*
X-7875D01*
G01X-15749D02*
X-63741D01*
G01X-7875Y1106300D02*
Y1111425D01*
G01Y1106300D02*
Y1092625D01*
G01D02*
G03X-1I3937J0D01*
G01Y1069005D02*
G03X-7875I-3937J0D01*
G01X-17894Y1268118D02*
X-7875D01*
G01Y1278280D02*
Y1268118D01*
G01Y1280567D02*
Y1275992D01*
G01X-15749Y1268118D02*
X-63741D01*
G01X-7875Y1309889D02*
G03X-1I3937J0D01*
G01Y1280567D02*
G03X-7875I-3937J0D01*
G01Y1309889D02*
G03X-1I3937J0D01*
G01Y1280567D02*
G03X-7875I-3937J0D01*
G01Y1309889D02*
Y1319285D01*
G01D02*
X-63741D01*
G01X-7875Y1889223D02*
Y1877953D01*
G01D02*
X-63741D01*
G01X-7875Y1912843D02*
Y1962926D01*
G01Y1912843D02*
G03X-1I3937J0D01*
G01Y1889223D02*
G03X-7875I-3937J0D01*
G01Y1912843D02*
G03X-1I3937J0D01*
G01Y1889223D02*
G03X-7875I-3937J0D01*
G01X-1Y1962926D02*
G03X-7875I-3937J0D01*
G01X-1D02*
G03X-7875I-3937J0D01*
G01Y1986546D02*
Y1992126D01*
G01D02*
X-63741D01*
G01X-7875Y1986546D02*
G03X-1I3937J0D01*
G01X-7875D02*
G03X-1I3937J0D01*
G01X1041337Y24677D02*
Y0D01*
G01Y217343D02*
Y48297D01*
G01Y0D02*
X1097204D01*
G01X1033463Y48297D02*
G03X1041337I3937J0D01*
G01Y24677D02*
G03X1033463I-3937J0D01*
G01Y48297D02*
G03X1041337I3937J0D01*
G01Y24677D02*
G03X1033463I-3937J0D01*
G01X1041337Y217343D02*
G03X1033463I-3937J0D01*
G01X1041337D02*
G03X1033463I-3937J0D01*
G01X1041337Y445039D02*
Y240963D01*
G01X1033463D02*
G03X1041337I3937J0D01*
G01X1033463D02*
G03X1041337I3937J0D01*
G01Y697474D02*
Y468601D01*
G01X1033463Y468659D02*
G03X1041337I3937J0D01*
G01Y445039D02*
G03X1033463I-3937J0D01*
G01Y468659D02*
G03X1041337I3937J0D01*
G01Y445039D02*
G03X1033463I-3937J0D01*
G01X1041337Y996851D02*
Y721093D01*
G01X1033463D02*
G03X1041337I3937J0D01*
G01Y697474D02*
G03X1033463I-3937J-1D01*
G01Y721093D02*
G03X1041337I3937J0D01*
G01Y697474D02*
G03X1033463I-3937J-1D01*
G01X1041337Y1344059D02*
Y1020472D01*
G01X1033463D02*
G03X1041337I3937J0D01*
G01Y996851D02*
G03X1033463I-3937J1D01*
G01Y1020472D02*
G03X1041337I3937J0D01*
G01Y996851D02*
G03X1033463I-3937J1D01*
G01X1041337Y1367679D02*
Y1393701D01*
G01X1033463Y1367679D02*
G03X1041337I3937J0D01*
G01Y1344059D02*
G03X1033463I-3937J0D01*
G01Y1367679D02*
G03X1041337I3937J0D01*
G01Y1344059D02*
G03X1033463I-3937J0D01*
G01X1041337Y1393701D02*
X1097204D01*
G01X1041337Y1733129D02*
Y1716535D01*
G01X1065042D02*
X1041337D01*
G01X1056337D02*
X1097204D01*
G01X1041337Y1739719D02*
Y1731535D01*
G01Y1959242D02*
Y1763311D01*
G01X1033463Y1763339D02*
G03X1041337I3937J0D01*
G01Y1739719D02*
G03X1033463I-3937J0D01*
G01Y1763339D02*
G03X1041337I3937J0D01*
G01Y1739719D02*
G03X1033463I-3937J0D01*
G01X1041337Y1959242D02*
G03X1033463I-3937J0D01*
G01X1041337D02*
G03X1033463I-3937J0D01*
G01X1041337Y1992126D02*
X1097204D01*
G01X1041337Y1982862D02*
Y1992126D01*
G01X1033463Y1982862D02*
G03X1041337I3937J0D01*
G01X1033463D02*
G03X1041337I3937J0D01*
G01X1112204Y648419D02*
Y15000D01*
G01X1097204Y0D02*
G03X1112204Y15000I0J15000D01*
G01Y656293D02*
G03Y648419I0J-3937D01*
G01Y1378701D02*
Y656293D01*
G01Y1378701D02*
G03X1097204Y1393701I-15000J0D01*
G01Y1716535D02*
G03X1112204Y1731535I0J15000D01*
G01Y1977126D02*
Y1731535D01*
G01Y1977126D02*
G03X1097204Y1992126I-15000J0D01*
M02*
